# T6G (Grand Teton) — schematic netlist excerpt (pin names and nets, part order shuffled) for the footprints in the layout excerpt that follows; sources: Cadence DE-HDL packaged netlist, KiCad conversion of 04192023_DAF0TMB3IC0_F0TG_MB_C_brd_V02_OCP.brd

C932  Q_CAP_DIFFBUS  DIFF BUS_0.22UF 6.3V 20% X6S  pkg C0201  page 63 : \1\ = P5E_CPU0_P0_TX_C_DN<0> ; \2\ = P5E_CPU0_P0_TX_DN<0>
C694  Q_CAP_DIFFBUS  DIFF BUS_0.22UF 6.3V 20% X6S  pkg C0201  page 67 : \1\ = P5E_CPU1_G1_TX_C_DN<7> ; \2\ = P5E_CPU1_G1_TX_DN<7>
C2614  Q_CAP  22UF 4V 20% X6S  pkg C0402  page 70 : A = PVDD11_S3_P0 ; B = GND
R781  Q_RES  4.7K 5% EMPTY  pkg 0201LF  page 331 : A = P1V8_CPU1_RT_1D ; B = GPIO2_RT_CPU1_P1
R694  Q_RES  33.2 1% CHIP  pkg 0201LF  page 344 : A = SMB_RT_CPU1_P2_ROM_R_SDA ; B = SMB_RT_CPU1_P2_ROM_SDA

(kicad_pcb
	(version 20260206)
	(generator "pcbnew")
	(generator_version "10.0")
	(general
		(thickness 1.6)
		(legacy_teardrops no)
	)
	(paper "A4")
	(title_block
		(title "04192023_DAF0TMB3IC0_F0TG_MB_C_brd_V02_OCP.brd")
		(comment 1 "Grand Teton / footprints 3208-3212 of 8354")
	)
	(layers
		(0 "F.Cu" signal "TOP")
		(4 "In1.Cu" signal "GND")
		(6 "In2.Cu" signal "IN1")
		(8 "In3.Cu" signal "GND1")
		(10 "In4.Cu" signal "IN2")
		(12 "In5.Cu" signal "GND2")
		(14 "In6.Cu" signal "IN3")
		(16 "In7.Cu" signal "GND3")
		(18 "In8.Cu" signal "VCC")
		(20 "In9.Cu" signal "VCC1")
		(22 "In10.Cu" signal "GND4")
		(24 "In11.Cu" signal "IN4")
		(26 "In12.Cu" signal "GND5")
		(28 "In13.Cu" signal "IN5")
		(30 "In14.Cu" signal "GND6")
		(32 "In15.Cu" signal "IN6")
		(34 "In16.Cu" signal "GND7")
		(2 "B.Cu" signal "BOTTOM")
		(9 "F.Adhes" user "F.Adhesive")
		(11 "B.Adhes" user "B.Adhesive")
		(13 "F.Paste" user "Package Geometry/Pastemask Top")
		(15 "B.Paste" user "Package Geometry/Pastemask Bottom")
		(5 "F.SilkS" user "Ref Des/Silkscreen Top")
		(7 "B.SilkS" user "Ref Des/Silkscreen Bottom")
		(1 "F.Mask" user "Board Geometry/Soldermask Top")
		(3 "B.Mask" user "Board Geometry/Soldermask Bottom")
		(17 "Dwgs.User" user "User.Drawings")
		(19 "Cmts.User" user "User.Comments")
		(21 "Eco1.User" user "User.Eco1")
		(23 "Eco2.User" user "User.Eco2")
		(25 "Edge.Cuts" user "Board Geometry/Outline")
		(27 "Margin" user)
		(31 "F.CrtYd" user "Package Geometry/Place Bound Top")
		(29 "B.CrtYd" user "Package Geometry/Place Bound Bottom")
		(35 "F.Fab" user "Ref Des/Assembly Top")
		(33 "B.Fab" user "Ref Des/Assembly Bottom")
	)
	(footprint ""
		(layer "F.Cu")
		(at 358.796082 -258.795012)
		(property "Reference" "C2614"
			(at 0 0 0)
			(layer "F.SilkS")
			(hide yes)
			(effects
				(font
					(size 1.27 1.27)
				)
			)
		)
		(property "Value" ""
			(at 0 0 0)
			(layer "F.Fab")
			(effects
				(font
					(size 1.27 1.27)
				)
			)
		)
		(duplicate_pad_numbers_are_jumpers no)
		(fp_line
			(start -0.7874 -0.4064)
			(end 0.7874 -0.4064)
			(stroke
				(width 0.1524)
				(type default)
			)
			(layer "F.SilkS")
		)
		(fp_line
			(start -0.7874 0.4064)
			(end -0.7874 -0.4064)
			(stroke
				(width 0.1524)
				(type default)
			)
			(layer "F.SilkS")
		)
		(fp_line
			(start 0.7874 -0.4064)
			(end 0.7874 0.4064)
			(stroke
				(width 0.1524)
				(type default)
			)
			(layer "F.SilkS")
		)
		(fp_line
			(start 0.7874 0.4064)
			(end -0.7874 0.4064)
			(stroke
				(width 0.1524)
				(type default)
			)
			(layer "F.SilkS")
		)
		(fp_line
			(start -0.67945 -0.305054)
			(end -0.12065 -0.305054)
			(stroke
				(width 0.1)
				(type default)
			)
			(layer "F.Fab")
		)
		(fp_line
			(start -0.67945 0.3048)
			(end -0.67945 -0.305054)
			(stroke
				(width 0.1)
				(type default)
			)
			(layer "F.Fab")
		)
		(fp_line
			(start -0.12065 -0.305054)
			(end -0.12065 -0.2794)
			(stroke
				(width 0.1)
				(type default)
			)
			(layer "F.Fab")
		)
		(fp_line
			(start -0.12065 -0.2794)
			(end 0.12065 -0.2794)
			(stroke
				(width 0.1)
				(type default)
			)
			(layer "F.Fab")
		)
		(fp_line
			(start -0.12065 0.2794)
			(end -0.12065 0.3048)
			(stroke
				(width 0.1)
				(type default)
			)
			(layer "F.Fab")
		)
		(fp_line
			(start -0.12065 0.3048)
			(end -0.67945 0.3048)
			(stroke
				(width 0.1)
				(type default)
			)
			(layer "F.Fab")
		)
		(fp_line
			(start 0.120396 0.2794)
			(end -0.12065 0.2794)
			(stroke
				(width 0.1)
				(type default)
			)
			(layer "F.Fab")
		)
		(fp_line
			(start 0.120396 0.3048)
			(end 0.120396 0.2794)
			(stroke
				(width 0.1)
				(type default)
			)
			(layer "F.Fab")
		)
		(fp_line
			(start 0.12065 -0.3048)
			(end 0.67945 -0.3048)
			(stroke
				(width 0.1)
				(type default)
			)
			(layer "F.Fab")
		)
		(fp_line
			(start 0.12065 -0.2794)
			(end 0.12065 -0.3048)
			(stroke
				(width 0.1)
				(type default)
			)
			(layer "F.Fab")
		)
		(fp_line
			(start 0.67945 -0.3048)
			(end 0.67945 0.3048)
			(stroke
				(width 0.1)
				(type default)
			)
			(layer "F.Fab")
		)
		(fp_line
			(start 0.67945 0.3048)
			(end 0.120396 0.3048)
			(stroke
				(width 0.1)
				(type default)
			)
			(layer "F.Fab")
		)
		(pad "1" smd circle
			(at -0.40005 0)
			(size 0 0)
			(layers "F.Cu" "F.Mask" "F.Paste")
			(net "PVDD11_S3_P0")
		)
		(pad "2" smd circle
			(at 0.40005 0)
			(size 0 0)
			(layers "F.Cu" "F.Mask" "F.Paste")
			(net "GND")
		)
	)
	(footprint ""
		(layer "F.Cu")
		(at 298.967144 -389.86206 180)
		(property "Reference" "C932"
			(at 0 0 180)
			(layer "F.SilkS")
			(hide yes)
			(effects
				(font
					(size 1.27 1.27)
				)
			)
		)
		(property "Value" ""
			(at 0 0 180)
			(layer "F.Fab")
			(effects
				(font
					(size 1.27 1.27)
				)
			)
		)
		(duplicate_pad_numbers_are_jumpers no)
		(fp_line
			(start 0.299974 0.150114)
			(end -0.299974 0.150114)
			(stroke
				(width 0.1)
				(type default)
			)
			(layer "F.Fab")
		)
		(fp_line
			(start 0.299974 -0.150114)
			(end 0.299974 0.150114)
			(stroke
				(width 0.1)
				(type default)
			)
			(layer "F.Fab")
		)
		(fp_line
			(start -0.299974 0.150114)
			(end -0.299974 -0.150114)
			(stroke
				(width 0.1)
				(type default)
			)
			(layer "F.Fab")
		)
		(fp_line
			(start -0.299974 -0.150114)
			(end 0.299974 -0.150114)
			(stroke
				(width 0.1)
				(type default)
			)
			(layer "F.Fab")
		)
		(pad "1" smd rect
			(at -0.2667 0 180)
			(size 0.3048 0.381)
			(layers "F.Cu" "F.Mask" "F.Paste")
			(net "P5E_CPU0_P0_TX_C_DN<0>")
		)
		(pad "2" smd rect
			(at 0.2667 0 180)
			(size 0.3048 0.381)
			(layers "F.Cu" "F.Mask" "F.Paste")
			(net "P5E_CPU0_P0_TX_DN<0>")
		)
	)
	(footprint ""
		(layer "F.Cu")
		(at 74.5236 -385.48056)
		(property "Reference" "R781"
			(at 0 0 0)
			(layer "F.SilkS")
			(hide yes)
			(effects
				(font
					(size 1.27 1.27)
				)
			)
		)
		(property "Value" ""
			(at 0 0 0)
			(layer "F.Fab")
			(effects
				(font
					(size 1.27 1.27)
				)
			)
		)
		(duplicate_pad_numbers_are_jumpers no)
		(fp_line
			(start -0.32512 -0.175006)
			(end 0.32512 -0.175006)
			(stroke
				(width 0.1)
				(type default)
			)
			(layer "F.Fab")
		)
		(fp_line
			(start -0.32512 0.175006)
			(end -0.32512 -0.175006)
			(stroke
				(width 0.1)
				(type default)
			)
			(layer "F.Fab")
		)
		(fp_line
			(start 0.32512 -0.175006)
			(end 0.32512 0.175006)
			(stroke
				(width 0.1)
				(type default)
			)
			(layer "F.Fab")
		)
		(fp_line
			(start 0.32512 0.175006)
			(end -0.32512 0.175006)
			(stroke
				(width 0.1)
				(type default)
			)
			(layer "F.Fab")
		)
		(pad "1" smd rect
			(at -0.2667 0)
			(size 0.3048 0.381)
			(layers "F.Cu" "F.Mask" "F.Paste")
			(net "P1V8_CPU1_RT_1D")
		)
		(pad "2" smd rect
			(at 0.2667 0 180)
			(size 0.3048 0.381)
			(layers "F.Cu" "F.Mask" "F.Paste")
			(net "GPIO2_RT_CPU1_P1")
		)
	)
	(footprint ""
		(layer "F.Cu")
		(at 37.860478 -16.099536 90)
		(property "Reference" "C694"
			(at 0 0 90)
			(layer "F.SilkS")
			(hide yes)
			(effects
				(font
					(size 1.27 1.27)
				)
			)
		)
		(property "Value" ""
			(at 0 0 90)
			(layer "F.Fab")
			(effects
				(font
					(size 1.27 1.27)
				)
			)
		)
		(duplicate_pad_numbers_are_jumpers no)
		(fp_line
			(start 0.299974 -0.150114)
			(end 0.299974 0.150114)
			(stroke
				(width 0.1)
				(type default)
			)
			(layer "F.Fab")
		)
		(fp_line
			(start -0.299974 -0.150114)
			(end 0.299974 -0.150114)
			(stroke
				(width 0.1)
				(type default)
			)
			(layer "F.Fab")
		)
		(fp_line
			(start 0.299974 0.150114)
			(end -0.299974 0.150114)
			(stroke
				(width 0.1)
				(type default)
			)
			(layer "F.Fab")
		)
		(fp_line
			(start -0.299974 0.150114)
			(end -0.299974 -0.150114)
			(stroke
				(width 0.1)
				(type default)
			)
			(layer "F.Fab")
		)
		(pad "1" smd rect
			(at -0.2667 0 90)
			(size 0.3048 0.381)
			(layers "F.Cu" "F.Mask" "F.Paste")
			(net "P5E_CPU1_G1_TX_C_DN<7>")
		)
		(pad "2" smd rect
			(at 0.2667 0 90)
			(size 0.3048 0.381)
			(layers "F.Cu" "F.Mask" "F.Paste")
			(net "P5E_CPU1_G1_TX_DN<7>")
		)
	)
	(footprint ""
		(layer "F.Cu")
		(at 162.5092 -419.0492 90)
		(property "Reference" "R694"
			(at 0 0 90)
			(layer "F.SilkS")
			(hide yes)
			(effects
				(font
					(size 1.27 1.27)
				)
			)
		)
		(property "Value" ""
			(at 0 0 90)
			(layer "F.Fab")
			(effects
				(font
					(size 1.27 1.27)
				)
			)
		)
		(duplicate_pad_numbers_are_jumpers no)
		(fp_line
			(start 0.32512 -0.175006)
			(end 0.32512 0.175006)
			(stroke
				(width 0.1)
				(type default)
			)
			(layer "F.Fab")
		)
		(fp_line
			(start -0.32512 -0.175006)
			(end 0.32512 -0.175006)
			(stroke
				(width 0.1)
				(type default)
			)
			(layer "F.Fab")
		)
		(fp_line
			(start 0.32512 0.175006)
			(end -0.32512 0.175006)
			(stroke
				(width 0.1)
				(type default)
			)
			(layer "F.Fab")
		)
		(fp_line
			(start -0.32512 0.175006)
			(end -0.32512 -0.175006)
			(stroke
				(width 0.1)
				(type default)
			)
			(layer "F.Fab")
		)
		(pad "1" smd rect
			(at -0.2667 0 90)
			(size 0.3048 0.381)
			(layers "F.Cu" "F.Mask" "F.Paste")
			(net "SMB_RT_CPU1_P2_ROM_R_SDA")
		)
		(pad "2" smd rect
			(at 0.2667 0 270)
			(size 0.3048 0.381)
			(layers "F.Cu" "F.Mask" "F.Paste")
			(net "SMB_RT_CPU1_P2_ROM_SDA")
		)
	)
)
